(kicad_pcb
	(version 20260206)
	(generator "pcbnew")
	(generator_version "10.0")
	(general
		(thickness 1.6)
		(legacy_teardrops no)
	)
	(paper "A4")
	(title_block
		(title "Bryce Canyon_R.DPB_16317-1_OCP.brd")
		(comment 1 "Bryce Canyon / footprints 1296-1302 of 2099")
	)
	(layers
		(0 "F.Cu" signal "TOP")
		(4 "In1.Cu" signal "L2GND")
		(6 "In2.Cu" signal "L3")
		(8 "In3.Cu" signal "L4VCC")
		(10 "In4.Cu" signal "L5VCC")
		(12 "In5.Cu" signal "L6")
		(14 "In6.Cu" signal "L7GND")
		(2 "B.Cu" signal "BOTTOM")
		(9 "F.Adhes" user "F.Adhesive")
		(11 "B.Adhes" user "B.Adhesive")
		(13 "F.Paste" user "Package Geometry/Pastemask Top")
		(15 "B.Paste" user "Package Geometry/Pastemask Bottom")
		(5 "F.SilkS" user "Ref Des/Silkscreen Top")
		(7 "B.SilkS" user "Ref Des/Silkscreen Bottom")
		(1 "F.Mask" user "Board Geometry/Soldermask Top")
		(3 "B.Mask" user "Board Geometry/Soldermask Bottom")
		(17 "Dwgs.User" user "User.Drawings")
		(19 "Cmts.User" user "User.Comments")
		(21 "Eco1.User" user "User.Eco1")
		(23 "Eco2.User" user "User.Eco2")
		(25 "Edge.Cuts" user "Board Geometry/Outline")
		(27 "Margin" user)
		(31 "F.CrtYd" user "Package Geometry/Place Bound Top")
		(29 "B.CrtYd" user "Package Geometry/Place Bound Bottom")
		(35 "F.Fab" user "Ref Des/Assembly Top")
		(33 "B.Fab" user "Ref Des/Assembly Bottom")
	)
	(footprint ""
		(layer "F.Cu")
		(at 243.205 -215.265)
		(property "Reference" "R81"
			(at 0 0 0)
			(layer "F.SilkS")
			(hide yes)
			(effects
				(font
					(size 1.27 1.27)
				)
			)
		)
		(property "Value" "4K7R2F-GP"
			(at 0.064008 -3.993896 0)
			(unlocked yes)
			(layer "F.Fab")
			(hide yes)
			(effects
				(font
					(size 1.016 1.016)
					(thickness 0.1524)
				)
			)
		)
		(property "Device Type" "R402H16"
			(at 0.064008 -5.517896 0)
			(unlocked yes)
			(layer "F.Fab")
			(hide yes)
			(effects
				(font
					(size 1.016 1.016)
					(thickness 0.1524)
				)
			)
		)
		(duplicate_pad_numbers_are_jumpers no)
		(fp_line
			(start -0.508 -0.9398)
			(end -0.508 0.9398)
			(stroke
				(width 0.1524)
				(type default)
			)
			(layer "F.SilkS")
		)
		(fp_line
			(start 0.508 -0.9398)
			(end -0.508 -0.9398)
			(stroke
				(width 0.1524)
				(type default)
			)
			(layer "F.SilkS")
		)
		(fp_rect
			(start -0.508 0.9398)
			(end 0.508 -0.9398)
			(stroke
				(width 0)
				(type default)
			)
			(fill no)
			(layer "F.CrtYd")
		)
		(fp_rect
			(start -0.508 0.9398)
			(end 0.508 -0.9398)
			(stroke
				(width 0)
				(type default)
			)
			(fill no)
			(layer "F.Fab")
		)
		(pad "1" smd custom
			(at 0 -0.4445)
			(size 0.1397 0.1397)
			(layers "F.Cu" "F.Mask" "F.Paste")
			(net "IO_EXP3_A1")
			(options
				(clearance outline)
				(anchor circle)
			)
			(primitives
				(gr_poly
					(pts
						(arc
							(start -0.1778 -0.2794)
							(mid -0.249642 -0.249642)
							(end -0.2794 -0.1778)
						)
						(arc
							(start -0.2794 0.1778)
							(mid -0.249642 0.249642)
							(end -0.1778 0.2794)
						)
						(arc
							(start 0.1778 0.2794)
							(mid 0.249642 0.249642)
							(end 0.2794 0.1778)
						)
						(arc
							(start 0.2794 -0.1778)
							(mid 0.249642 -0.249642)
							(end 0.1778 -0.2794)
						)
					)
					(width 0)
					(fill yes)
				)
			)
		)
		(pad "2" smd custom
			(at 0 0.4445)
			(size 0.1397 0.1397)
			(layers "F.Cu" "F.Mask" "F.Paste")
			(net "GND")
			(options
				(clearance outline)
				(anchor circle)
			)
			(primitives
				(gr_poly
					(pts
						(arc
							(start -0.1778 -0.2794)
							(mid -0.249642 -0.249642)
							(end -0.2794 -0.1778)
						)
						(arc
							(start -0.2794 0.1778)
							(mid -0.249642 0.249642)
							(end -0.1778 0.2794)
						)
						(arc
							(start 0.1778 0.2794)
							(mid 0.249642 0.249642)
							(end 0.2794 0.1778)
						)
						(arc
							(start 0.2794 -0.1778)
							(mid 0.249642 -0.249642)
							(end 0.1778 -0.2794)
						)
					)
					(width 0)
					(fill yes)
				)
			)
		)
	)
	(footprint ""
		(layer "F.Cu")
		(at 458.0636 -13.2334)
		(property "Reference" "R137"
			(at 0 0 0)
			(layer "F.SilkS")
			(hide yes)
			(effects
				(font
					(size 1.27 1.27)
				)
			)
		)
		(property "Value" "0R2J-2-GP"
			(at 0.064008 -3.993896 0)
			(unlocked yes)
			(layer "F.Fab")
			(hide yes)
			(effects
				(font
					(size 1.016 1.016)
					(thickness 0.1524)
				)
			)
		)
		(property "Device Type" "R402H16"
			(at 0.064008 -5.517896 0)
			(unlocked yes)
			(layer "F.Fab")
			(hide yes)
			(effects
				(font
					(size 1.016 1.016)
					(thickness 0.1524)
				)
			)
		)
		(duplicate_pad_numbers_are_jumpers no)
		(fp_line
			(start -0.508 -0.9398)
			(end -0.508 0.9398)
			(stroke
				(width 0.1524)
				(type default)
			)
			(layer "F.SilkS")
		)
		(fp_line
			(start 0.508 -0.9398)
			(end -0.508 -0.9398)
			(stroke
				(width 0.1524)
				(type default)
			)
			(layer "F.SilkS")
		)
		(fp_rect
			(start -0.508 0.9398)
			(end 0.508 -0.9398)
			(stroke
				(width 0)
				(type default)
			)
			(fill no)
			(layer "F.CrtYd")
		)
		(fp_rect
			(start -0.508 0.9398)
			(end 0.508 -0.9398)
			(stroke
				(width 0)
				(type default)
			)
			(fill no)
			(layer "F.Fab")
		)
		(pad "1" smd custom
			(at 0 -0.4445)
			(size 0.1397 0.1397)
			(layers "F.Cu" "F.Mask" "F.Paste")
			(net "I2C_DPB_B_SCL_BUF")
			(options
				(clearance outline)
				(anchor circle)
			)
			(primitives
				(gr_poly
					(pts
						(arc
							(start -0.1778 -0.2794)
							(mid -0.249642 -0.249642)
							(end -0.2794 -0.1778)
						)
						(arc
							(start -0.2794 0.1778)
							(mid -0.249642 0.249642)
							(end -0.1778 0.2794)
						)
						(arc
							(start 0.1778 0.2794)
							(mid 0.249642 0.249642)
							(end 0.2794 0.1778)
						)
						(arc
							(start 0.2794 -0.1778)
							(mid 0.249642 -0.249642)
							(end 0.1778 -0.2794)
						)
					)
					(width 0)
					(fill yes)
				)
			)
		)
		(pad "2" smd custom
			(at 0 0.4445)
			(size 0.1397 0.1397)
			(layers "F.Cu" "F.Mask" "F.Paste")
			(net "TEMP2_SCL")
			(options
				(clearance outline)
				(anchor circle)
			)
			(primitives
				(gr_poly
					(pts
						(arc
							(start -0.1778 -0.2794)
							(mid -0.249642 -0.249642)
							(end -0.2794 -0.1778)
						)
						(arc
							(start -0.2794 0.1778)
							(mid -0.249642 0.249642)
							(end -0.1778 0.2794)
						)
						(arc
							(start 0.1778 0.2794)
							(mid 0.249642 0.249642)
							(end 0.2794 0.1778)
						)
						(arc
							(start 0.2794 -0.1778)
							(mid 0.249642 -0.249642)
							(end 0.1778 -0.2794)
						)
					)
					(width 0)
					(fill yes)
				)
			)
		)
	)
	(footprint ""
		(layer "F.Cu")
		(at 190.213488 -245.219474 90)
		(property "Reference" "C94"
			(at 0 0 90)
			(layer "F.SilkS")
			(hide yes)
			(effects
				(font
					(size 1.27 1.27)
				)
			)
		)
		(property "Value" "SCD01U16V1KX-GP"
			(at -2.8321 -1.7399 90)
			(unlocked yes)
			(layer "F.Fab")
			(hide yes)
			(effects
				(font
					(size 1.016 1.016)
					(thickness 0.1524)
				)
			)
		)
		(property "Device Type" "C0201H13"
			(at -2.8321 -3.2639 90)
			(unlocked yes)
			(layer "F.Fab")
			(hide yes)
			(effects
				(font
					(size 1.016 1.016)
					(thickness 0.1524)
				)
			)
		)
		(duplicate_pad_numbers_are_jumpers no)
		(fp_rect
			(start -0.2794 0.6477)
			(end 0.2794 -0.6477)
			(stroke
				(width 0)
				(type default)
			)
			(fill no)
			(layer "F.CrtYd")
		)
		(fp_rect
			(start -0.2794 0.6477)
			(end 0.2794 -0.6477)
			(stroke
				(width 0)
				(type default)
			)
			(fill no)
			(layer "F.Fab")
		)
		(pad "1" smd custom
			(at 0 -0.2794 90)
			(size 0.0762 0.0762)
			(layers "F.Cu" "F.Mask" "F.Paste")
			(net "SAS_HDD_RX_N5")
			(options
				(clearance outline)
				(anchor circle)
			)
			(primitives
				(gr_poly
					(pts
						(arc
							(start 0.1524 -0.127)
							(mid 0.137521 -0.162921)
							(end 0.1016 -0.1778)
						)
						(arc
							(start -0.1016 -0.1778)
							(mid -0.137521 -0.162921)
							(end -0.1524 -0.127)
						)
						(arc
							(start -0.1524 0.127)
							(mid -0.137521 0.162921)
							(end -0.1016 0.1778)
						)
						(arc
							(start 0.1016 0.1778)
							(mid 0.137521 0.162921)
							(end 0.1524 0.127)
						)
					)
					(width 0)
					(fill yes)
				)
			)
		)
		(pad "2" smd custom
			(at 0 0.2794 90)
			(size 0.0762 0.0762)
			(layers "F.Cu" "F.Mask" "F.Paste")
			(net "PHY_SCC_B_TO_DRV_B_5_DN")
			(options
				(clearance outline)
				(anchor circle)
			)
			(primitives
				(gr_poly
					(pts
						(arc
							(start 0.1524 -0.127)
							(mid 0.137521 -0.162921)
							(end 0.1016 -0.1778)
						)
						(arc
							(start -0.1016 -0.1778)
							(mid -0.137521 -0.162921)
							(end -0.1524 -0.127)
						)
						(arc
							(start -0.1524 0.127)
							(mid -0.137521 0.162921)
							(end -0.1016 0.1778)
						)
						(arc
							(start 0.1016 0.1778)
							(mid 0.137521 0.162921)
							(end 0.1524 0.127)
						)
					)
					(width 0)
					(fill yes)
				)
			)
		)
	)
	(footprint ""
		(layer "F.Cu")
		(at 161.925 -266.065 90)
		(property "Reference" "R225"
			(at 0 0 90)
			(layer "F.SilkS")
			(hide yes)
			(effects
				(font
					(size 1.27 1.27)
				)
			)
		)
		(property "Value" "220R3F-1-GP"
			(at -0.0254 -2.5146 90)
			(unlocked yes)
			(layer "F.Fab")
			(hide yes)
			(effects
				(font
					(size 1.016 1.016)
					(thickness 0.1524)
				)
			)
		)
		(property "Device Type" "R603H22"
			(at -0.0254 -4.0386 90)
			(unlocked yes)
			(layer "F.Fab")
			(hide yes)
			(effects
				(font
					(size 1.016 1.016)
					(thickness 0.1524)
				)
			)
		)
		(duplicate_pad_numbers_are_jumpers no)
		(fp_line
			(start 0.2032 0)
			(end 0.4826 0)
			(stroke
				(width 0.2032)
				(type default)
			)
			(layer "F.SilkS")
		)
		(fp_line
			(start -0.4826 0)
			(end -0.2032 0)
			(stroke
				(width 0.2032)
				(type default)
			)
			(layer "F.SilkS")
		)
		(fp_rect
			(start -0.5842 1.3335)
			(end 0.5842 -1.3335)
			(stroke
				(width 0)
				(type default)
			)
			(fill no)
			(layer "F.CrtYd")
		)
		(fp_rect
			(start -0.5842 1.3335)
			(end 0.5842 -1.3335)
			(stroke
				(width 0)
				(type default)
			)
			(fill no)
			(layer "F.Fab")
		)
		(pad "1" smd custom
			(at 0 -0.762 90)
			(size 0.2159 0.2159)
			(layers "F.Cu" "F.Mask" "F.Paste")
			(net "HDD_PRSNT_4")
			(options
				(clearance outline)
				(anchor circle)
			)
			(primitives
				(gr_poly
					(pts
						(arc
							(start -0.3302 -0.4318)
							(mid -0.402042 -0.402042)
							(end -0.4318 -0.3302)
						)
						(arc
							(start -0.4318 0.3302)
							(mid -0.402042 0.402042)
							(end -0.3302 0.4318)
						)
						(arc
							(start 0.3302 0.4318)
							(mid 0.402042 0.402042)
							(end 0.4318 0.3302)
						)
						(arc
							(start 0.4318 -0.3302)
							(mid 0.402042 -0.402042)
							(end 0.3302 -0.4318)
						)
					)
					(width 0)
					(fill yes)
				)
			)
		)
		(pad "2" smd custom
			(at 0 0.762 90)
			(size 0.2159 0.2159)
			(layers "F.Cu" "F.Mask" "F.Paste")
			(net "DRIVE_B_4_INS")
			(options
				(clearance outline)
				(anchor circle)
			)
			(primitives
				(gr_poly
					(pts
						(arc
							(start -0.3302 -0.4318)
							(mid -0.402042 -0.402042)
							(end -0.4318 -0.3302)
						)
						(arc
							(start -0.4318 0.3302)
							(mid -0.402042 0.402042)
							(end -0.3302 0.4318)
						)
						(arc
							(start 0.3302 0.4318)
							(mid 0.402042 0.402042)
							(end 0.4318 0.3302)
						)
						(arc
							(start 0.4318 -0.3302)
							(mid 0.402042 -0.402042)
							(end 0.3302 -0.4318)
						)
					)
					(width 0)
					(fill yes)
				)
			)
		)
	)
	(footprint ""
		(layer "F.Cu")
		(at 187.891928 -372.423436 90)
		(property "Reference" "R178"
			(at 0 0 90)
			(layer "F.SilkS")
			(hide yes)
			(effects
				(font
					(size 1.27 1.27)
				)
			)
		)
		(property "Value" "4K7R2F-GP"
			(at 0.064008 -3.993896 90)
			(unlocked yes)
			(layer "F.Fab")
			(hide yes)
			(effects
				(font
					(size 1.016 1.016)
					(thickness 0.1524)
				)
			)
		)
		(property "Device Type" "R402H16"
			(at 0.064008 -5.517896 90)
			(unlocked yes)
			(layer "F.Fab")
			(hide yes)
			(effects
				(font
					(size 1.016 1.016)
					(thickness 0.1524)
				)
			)
		)
		(duplicate_pad_numbers_are_jumpers no)
		(fp_line
			(start 0.508 -0.9398)
			(end -0.508 -0.9398)
			(stroke
				(width 0.1524)
				(type default)
			)
			(layer "F.SilkS")
		)
		(fp_line
			(start -0.508 -0.9398)
			(end -0.508 0.9398)
			(stroke
				(width 0.1524)
				(type default)
			)
			(layer "F.SilkS")
		)
		(fp_rect
			(start -0.508 0.9398)
			(end 0.508 -0.9398)
			(stroke
				(width 0)
				(type default)
			)
			(fill no)
			(layer "F.CrtYd")
		)
		(fp_rect
			(start -0.508 0.9398)
			(end 0.508 -0.9398)
			(stroke
				(width 0)
				(type default)
			)
			(fill no)
			(layer "F.Fab")
		)
		(pad "1" smd custom
			(at 0 -0.4445 90)
			(size 0.1397 0.1397)
			(layers "F.Cu" "F.Mask" "F.Paste")
			(net "FAN_BLUE_LED1")
			(options
				(clearance outline)
				(anchor circle)
			)
			(primitives
				(gr_poly
					(pts
						(arc
							(start -0.1778 -0.2794)
							(mid -0.249642 -0.249642)
							(end -0.2794 -0.1778)
						)
						(arc
							(start -0.2794 0.1778)
							(mid -0.249642 0.249642)
							(end -0.1778 0.2794)
						)
						(arc
							(start 0.1778 0.2794)
							(mid 0.249642 0.249642)
							(end 0.2794 0.1778)
						)
						(arc
							(start 0.2794 -0.1778)
							(mid 0.249642 -0.249642)
							(end 0.1778 -0.2794)
						)
					)
					(width 0)
					(fill yes)
				)
			)
		)
		(pad "2" smd custom
			(at 0 0.4445 90)
			(size 0.1397 0.1397)
			(layers "F.Cu" "F.Mask" "F.Paste")
			(net "P12V_IN")
			(options
				(clearance outline)
				(anchor circle)
			)
			(primitives
				(gr_poly
					(pts
						(arc
							(start -0.1778 -0.2794)
							(mid -0.249642 -0.249642)
							(end -0.2794 -0.1778)
						)
						(arc
							(start -0.2794 0.1778)
							(mid -0.249642 0.249642)
							(end -0.1778 0.2794)
						)
						(arc
							(start 0.1778 0.2794)
							(mid 0.249642 0.249642)
							(end 0.2794 0.1778)
						)
						(arc
							(start 0.2794 -0.1778)
							(mid 0.249642 -0.249642)
							(end 0.1778 -0.2794)
						)
					)
					(width 0)
					(fill yes)
				)
			)
		)
	)
	(footprint ""
		(layer "F.Cu")
		(at 117.602 -133.4262 -90)
		(property "Reference" "R423"
			(at 0 0 270)
			(layer "F.SilkS")
			(hide yes)
			(effects
				(font
					(size 1.27 1.27)
				)
			)
		)
		(property "Value" "1KR2F-3-GP"
			(at 0.064008 -3.993896 270)
			(unlocked yes)
			(layer "F.Fab")
			(hide yes)
			(effects
				(font
					(size 1.016 1.016)
					(thickness 0.1524)
				)
			)
		)
		(property "Device Type" "R402H16"
			(at 0.064008 -5.517896 270)
			(unlocked yes)
			(layer "F.Fab")
			(hide yes)
			(effects
				(font
					(size 1.016 1.016)
					(thickness 0.1524)
				)
			)
		)
		(duplicate_pad_numbers_are_jumpers no)
		(fp_line
			(start -0.508 -0.9398)
			(end -0.508 0.9398)
			(stroke
				(width 0.1524)
				(type default)
			)
			(layer "F.SilkS")
		)
		(fp_line
			(start 0.508 -0.9398)
			(end -0.508 -0.9398)
			(stroke
				(width 0.1524)
				(type default)
			)
			(layer "F.SilkS")
		)
		(fp_rect
			(start -0.508 0.9398)
			(end 0.508 -0.9398)
			(stroke
				(width 0)
				(type default)
			)
			(fill no)
			(layer "F.CrtYd")
		)
		(fp_rect
			(start -0.508 0.9398)
			(end 0.508 -0.9398)
			(stroke
				(width 0)
				(type default)
			)
			(fill no)
			(layer "F.Fab")
		)
		(pad "1" smd custom
			(at 0 -0.4445 270)
			(size 0.1397 0.1397)
			(layers "F.Cu" "F.Mask" "F.Paste")
			(net "P3V3_STBY_B")
			(options
				(clearance outline)
				(anchor circle)
			)
			(primitives
				(gr_poly
					(pts
						(arc
							(start -0.1778 -0.2794)
							(mid -0.249642 -0.249642)
							(end -0.2794 -0.1778)
						)
						(arc
							(start -0.2794 0.1778)
							(mid -0.249642 0.249642)
							(end -0.1778 0.2794)
						)
						(arc
							(start 0.1778 0.2794)
							(mid 0.249642 0.249642)
							(end 0.2794 0.1778)
						)
						(arc
							(start 0.2794 -0.1778)
							(mid 0.249642 -0.249642)
							(end 0.1778 -0.2794)
						)
					)
					(width 0)
					(fill yes)
				)
			)
		)
		(pad "2" smd custom
			(at 0 0.4445 270)
			(size 0.1397 0.1397)
			(layers "F.Cu" "F.Mask" "F.Paste")
			(net "SW_PWR_R_HDD15")
			(options
				(clearance outline)
				(anchor circle)
			)
			(primitives
				(gr_poly
					(pts
						(arc
							(start -0.1778 -0.2794)
							(mid -0.249642 -0.249642)
							(end -0.2794 -0.1778)
						)
						(arc
							(start -0.2794 0.1778)
							(mid -0.249642 0.249642)
							(end -0.1778 0.2794)
						)
						(arc
							(start 0.1778 0.2794)
							(mid 0.249642 0.249642)
							(end 0.2794 0.1778)
						)
						(arc
							(start 0.2794 -0.1778)
							(mid 0.249642 -0.249642)
							(end 0.1778 -0.2794)
						)
					)
					(width 0)
					(fill yes)
				)
			)
		)
	)
	(footprint ""
		(layer "F.Cu")
		(at 395.605 -10.16 180)
		(property "Reference" "R814"
			(at 0 0 180)
			(layer "F.SilkS")
			(hide yes)
			(effects
				(font
					(size 1.27 1.27)
				)
			)
		)
		(property "Value" "100KR2F-L1-GP"
			(at 0.064008 -3.993896 180)
			(unlocked yes)
			(layer "F.Fab")
			(hide yes)
			(effects
				(font
					(size 1.016 1.016)
					(thickness 0.1524)
				)
			)
		)
		(property "Device Type" "R402H16"
			(at 0.064008 -5.517896 180)
			(unlocked yes)
			(layer "F.Fab")
			(hide yes)
			(effects
				(font
					(size 1.016 1.016)
					(thickness 0.1524)
				)
			)
		)
		(duplicate_pad_numbers_are_jumpers no)
		(fp_line
			(start 0.508 -0.9398)
			(end -0.508 -0.9398)
			(stroke
				(width 0.1524)
				(type default)
			)
			(layer "F.SilkS")
		)
		(fp_line
			(start -0.508 -0.9398)
			(end -0.508 0.9398)
			(stroke
				(width 0.1524)
				(type default)
			)
			(layer "F.SilkS")
		)
		(fp_rect
			(start -0.508 0.9398)
			(end 0.508 -0.9398)
			(stroke
				(width 0)
				(type default)
			)
			(fill no)
			(layer "F.CrtYd")
		)
		(fp_rect
			(start -0.508 0.9398)
			(end 0.508 -0.9398)
			(stroke
				(width 0)
				(type default)
			)
			(fill no)
			(layer "F.Fab")
		)
		(pad "1" smd custom
			(at 0 -0.4445 180)
			(size 0.1397 0.1397)
			(layers "F.Cu" "F.Mask" "F.Paste")
			(net "P3V3_STBY_B")
			(options
				(clearance outline)
				(anchor circle)
			)
			(primitives
				(gr_poly
					(pts
						(arc
							(start -0.1778 -0.2794)
							(mid -0.249642 -0.249642)
							(end -0.2794 -0.1778)
						)
						(arc
							(start -0.2794 0.1778)
							(mid -0.249642 0.249642)
							(end -0.1778 0.2794)
						)
						(arc
							(start 0.1778 0.2794)
							(mid 0.249642 0.249642)
							(end 0.2794 0.1778)
						)
						(arc
							(start 0.2794 -0.1778)
							(mid 0.249642 -0.249642)
							(end 0.1778 -0.2794)
						)
					)
					(width 0)
					(fill yes)
				)
			)
		)
		(pad "2" smd custom
			(at 0 0.4445 180)
			(size 0.1397 0.1397)
			(layers "F.Cu" "F.Mask" "F.Paste")
			(net "SW_PWR_R_HDD32")
			(options
				(clearance outline)
				(anchor circle)
			)
			(primitives
				(gr_poly
					(pts
						(arc
							(start -0.1778 -0.2794)
							(mid -0.249642 -0.249642)
							(end -0.2794 -0.1778)
						)
						(arc
							(start -0.2794 0.1778)
							(mid -0.249642 0.249642)
							(end -0.1778 0.2794)
						)
						(arc
							(start 0.1778 0.2794)
							(mid 0.249642 0.249642)
							(end 0.2794 0.1778)
						)
						(arc
							(start 0.2794 -0.1778)
							(mid 0.249642 -0.249642)
							(end 0.1778 -0.2794)
						)
					)
					(width 0)
					(fill yes)
				)
			)
		)
	)
)
